# T6G (Grand Teton) — schematic netlist excerpt (pin names and nets, part order shuffled) for the footprints in the layout excerpt that follows; sources: Cadence DE-HDL packaged netlist, KiCad conversion of 04192023_DAF0TMB3IC0_F0TG_MB_C_brd_V02_OCP.brd

R159  Q_RES  33 5% CHIP  pkg 0402LF  page 81 : A = CPU0_JTAG_BUF_OE ; B = CPU0_JTAG_BUF_R_OE
PR6551  Q_RES  0 5% EMPTY  pkg 0402LF  page 363 : A = P3V3_AUX ; B = P0V9_RETIMER_CPU0_PVCC
C767  Q_CAP_DIFFBUS  DIFF BUS_0.22UF 6.3V 20% X6S  pkg C0201  page 66 : \1\ = P5E_CPU1_P2_TX_C_DP<3> ; \2\ = P5E_CPU1_P2_TX_DP<3>

(kicad_pcb
	(version 20260206)
	(generator "pcbnew")
	(generator_version "10.0")
	(general
		(thickness 1.6)
		(legacy_teardrops no)
	)
	(paper "A4")
	(title_block
		(title "04192023_DAF0TMB3IC0_F0TG_MB_C_brd_V02_OCP.brd")
		(comment 1 "Grand Teton / footprints 2056-2058 of 8354")
	)
	(layers
		(0 "F.Cu" signal "TOP")
		(4 "In1.Cu" signal "GND")
		(6 "In2.Cu" signal "IN1")
		(8 "In3.Cu" signal "GND1")
		(10 "In4.Cu" signal "IN2")
		(12 "In5.Cu" signal "GND2")
		(14 "In6.Cu" signal "IN3")
		(16 "In7.Cu" signal "GND3")
		(18 "In8.Cu" signal "VCC")
		(20 "In9.Cu" signal "VCC1")
		(22 "In10.Cu" signal "GND4")
		(24 "In11.Cu" signal "IN4")
		(26 "In12.Cu" signal "GND5")
		(28 "In13.Cu" signal "IN5")
		(30 "In14.Cu" signal "GND6")
		(32 "In15.Cu" signal "IN6")
		(34 "In16.Cu" signal "GND7")
		(2 "B.Cu" signal "BOTTOM")
		(9 "F.Adhes" user "F.Adhesive")
		(11 "B.Adhes" user "B.Adhesive")
		(13 "F.Paste" user "Package Geometry/Pastemask Top")
		(15 "B.Paste" user "Package Geometry/Pastemask Bottom")
		(5 "F.SilkS" user "Ref Des/Silkscreen Top")
		(7 "B.SilkS" user "Ref Des/Silkscreen Bottom")
		(1 "F.Mask" user "Board Geometry/Soldermask Top")
		(3 "B.Mask" user "Board Geometry/Soldermask Bottom")
		(17 "Dwgs.User" user "User.Drawings")
		(19 "Cmts.User" user "User.Comments")
		(21 "Eco1.User" user "User.Eco1")
		(23 "Eco2.User" user "User.Eco2")
		(25 "Edge.Cuts" user "Board Geometry/Outline")
		(27 "Margin" user)
		(31 "F.CrtYd" user "Package Geometry/Place Bound Top")
		(29 "B.CrtYd" user "Package Geometry/Place Bound Bottom")
		(35 "F.Fab" user "Ref Des/Assembly Top")
		(33 "B.Fab" user "Ref Des/Assembly Bottom")
	)
	(footprint ""
		(layer "F.Cu")
		(at 144.319244 -370.57203 -90)
		(property "Reference" "C767"
			(at 0 0 270)
			(layer "F.SilkS")
			(hide yes)
			(effects
				(font
					(size 1.27 1.27)
				)
			)
		)
		(property "Value" ""
			(at 0 0 270)
			(layer "F.Fab")
			(effects
				(font
					(size 1.27 1.27)
				)
			)
		)
		(duplicate_pad_numbers_are_jumpers no)
		(fp_line
			(start -0.299974 0.150114)
			(end -0.299974 -0.150114)
			(stroke
				(width 0.1)
				(type default)
			)
			(layer "F.Fab")
		)
		(fp_line
			(start 0.299974 0.150114)
			(end -0.299974 0.150114)
			(stroke
				(width 0.1)
				(type default)
			)
			(layer "F.Fab")
		)
		(fp_line
			(start -0.299974 -0.150114)
			(end 0.299974 -0.150114)
			(stroke
				(width 0.1)
				(type default)
			)
			(layer "F.Fab")
		)
		(fp_line
			(start 0.299974 -0.150114)
			(end 0.299974 0.150114)
			(stroke
				(width 0.1)
				(type default)
			)
			(layer "F.Fab")
		)
		(pad "1" smd rect
			(at -0.2667 0 270)
			(size 0.3048 0.381)
			(layers "F.Cu" "F.Mask" "F.Paste")
			(net "P5E_CPU1_P2_TX_C_DP<3>")
		)
		(pad "2" smd rect
			(at 0.2667 0 270)
			(size 0.3048 0.381)
			(layers "F.Cu" "F.Mask" "F.Paste")
			(net "P5E_CPU1_P2_TX_DP<3>")
		)
	)
	(footprint ""
		(layer "F.Cu")
		(at 438.455308 -405.788622 -90)
		(property "Reference" "PR6551"
			(at 0 0 270)
			(layer "F.SilkS")
			(hide yes)
			(effects
				(font
					(size 1.27 1.27)
				)
			)
		)
		(property "Value" ""
			(at 0 0 270)
			(layer "F.Fab")
			(effects
				(font
					(size 1.27 1.27)
				)
			)
		)
		(duplicate_pad_numbers_are_jumpers no)
		(fp_line
			(start -0.7874 0.4064)
			(end -0.7874 -0.4064)
			(stroke
				(width 0.1524)
				(type default)
			)
			(layer "F.SilkS")
		)
		(fp_line
			(start 0.7874 0.4064)
			(end -0.7874 0.4064)
			(stroke
				(width 0.1524)
				(type default)
			)
			(layer "F.SilkS")
		)
		(fp_line
			(start -0.7874 -0.4064)
			(end 0.7874 -0.4064)
			(stroke
				(width 0.1524)
				(type default)
			)
			(layer "F.SilkS")
		)
		(fp_line
			(start 0.7874 -0.4064)
			(end 0.7874 0.4064)
			(stroke
				(width 0.1524)
				(type default)
			)
			(layer "F.SilkS")
		)
		(fp_line
			(start -0.67945 0.3048)
			(end -0.67945 -0.305054)
			(stroke
				(width 0.1)
				(type default)
			)
			(layer "F.Fab")
		)
		(fp_line
			(start -0.12065 0.3048)
			(end -0.67945 0.3048)
			(stroke
				(width 0.1)
				(type default)
			)
			(layer "F.Fab")
		)
		(fp_line
			(start 0.120396 0.3048)
			(end 0.120396 0.2794)
			(stroke
				(width 0.1)
				(type default)
			)
			(layer "F.Fab")
		)
		(fp_line
			(start 0.67945 0.3048)
			(end 0.120396 0.3048)
			(stroke
				(width 0.1)
				(type default)
			)
			(layer "F.Fab")
		)
		(fp_line
			(start -0.12065 0.2794)
			(end -0.12065 0.3048)
			(stroke
				(width 0.1)
				(type default)
			)
			(layer "F.Fab")
		)
		(fp_line
			(start 0.120396 0.2794)
			(end -0.12065 0.2794)
			(stroke
				(width 0.1)
				(type default)
			)
			(layer "F.Fab")
		)
		(fp_line
			(start -0.12065 -0.2794)
			(end 0.12065 -0.2794)
			(stroke
				(width 0.1)
				(type default)
			)
			(layer "F.Fab")
		)
		(fp_line
			(start 0.12065 -0.2794)
			(end 0.12065 -0.3048)
			(stroke
				(width 0.1)
				(type default)
			)
			(layer "F.Fab")
		)
		(fp_line
			(start 0.12065 -0.3048)
			(end 0.67945 -0.3048)
			(stroke
				(width 0.1)
				(type default)
			)
			(layer "F.Fab")
		)
		(fp_line
			(start 0.67945 -0.3048)
			(end 0.67945 0.3048)
			(stroke
				(width 0.1)
				(type default)
			)
			(layer "F.Fab")
		)
		(fp_line
			(start -0.67945 -0.305054)
			(end -0.12065 -0.305054)
			(stroke
				(width 0.1)
				(type default)
			)
			(layer "F.Fab")
		)
		(fp_line
			(start -0.12065 -0.305054)
			(end -0.12065 -0.2794)
			(stroke
				(width 0.1)
				(type default)
			)
			(layer "F.Fab")
		)
		(pad "1" smd circle
			(at -0.40005 0 270)
			(size 0 0)
			(layers "F.Cu" "F.Mask" "F.Paste")
			(net "P3V3_AUX")
		)
		(pad "2" smd circle
			(at 0.40005 0 270)
			(size 0 0)
			(layers "F.Cu" "F.Mask" "F.Paste")
			(net "P0V9_RETIMER_CPU0_PVCC")
		)
	)
	(footprint ""
		(layer "F.Cu")
		(at 181.868064 -133.58495 -90)
		(property "Reference" "R159"
			(at 0 0 270)
			(layer "F.SilkS")
			(hide yes)
			(effects
				(font
					(size 1.27 1.27)
				)
			)
		)
		(property "Value" ""
			(at 0 0 270)
			(layer "F.Fab")
			(effects
				(font
					(size 1.27 1.27)
				)
			)
		)
		(duplicate_pad_numbers_are_jumpers no)
		(fp_line
			(start -0.7874 0.4064)
			(end -0.7874 -0.4064)
			(stroke
				(width 0.1524)
				(type default)
			)
			(layer "F.SilkS")
		)
		(fp_line
			(start 0.7874 0.4064)
			(end -0.7874 0.4064)
			(stroke
				(width 0.1524)
				(type default)
			)
			(layer "F.SilkS")
		)
		(fp_line
			(start -0.7874 -0.4064)
			(end 0.7874 -0.4064)
			(stroke
				(width 0.1524)
				(type default)
			)
			(layer "F.SilkS")
		)
		(fp_line
			(start 0.7874 -0.4064)
			(end 0.7874 0.4064)
			(stroke
				(width 0.1524)
				(type default)
			)
			(layer "F.SilkS")
		)
		(fp_line
			(start -0.67945 0.3048)
			(end -0.67945 -0.305054)
			(stroke
				(width 0.1)
				(type default)
			)
			(layer "F.Fab")
		)
		(fp_line
			(start -0.12065 0.3048)
			(end -0.67945 0.3048)
			(stroke
				(width 0.1)
				(type default)
			)
			(layer "F.Fab")
		)
		(fp_line
			(start 0.120396 0.3048)
			(end 0.120396 0.2794)
			(stroke
				(width 0.1)
				(type default)
			)
			(layer "F.Fab")
		)
		(fp_line
			(start 0.67945 0.3048)
			(end 0.120396 0.3048)
			(stroke
				(width 0.1)
				(type default)
			)
			(layer "F.Fab")
		)
		(fp_line
			(start -0.12065 0.2794)
			(end -0.12065 0.3048)
			(stroke
				(width 0.1)
				(type default)
			)
			(layer "F.Fab")
		)
		(fp_line
			(start 0.120396 0.2794)
			(end -0.12065 0.2794)
			(stroke
				(width 0.1)
				(type default)
			)
			(layer "F.Fab")
		)
		(fp_line
			(start -0.12065 -0.2794)
			(end 0.12065 -0.2794)
			(stroke
				(width 0.1)
				(type default)
			)
			(layer "F.Fab")
		)
		(fp_line
			(start 0.12065 -0.2794)
			(end 0.12065 -0.3048)
			(stroke
				(width 0.1)
				(type default)
			)
			(layer "F.Fab")
		)
		(fp_line
			(start 0.12065 -0.3048)
			(end 0.67945 -0.3048)
			(stroke
				(width 0.1)
				(type default)
			)
			(layer "F.Fab")
		)
		(fp_line
			(start 0.67945 -0.3048)
			(end 0.67945 0.3048)
			(stroke
				(width 0.1)
				(type default)
			)
			(layer "F.Fab")
		)
		(fp_line
			(start -0.67945 -0.305054)
			(end -0.12065 -0.305054)
			(stroke
				(width 0.1)
				(type default)
			)
			(layer "F.Fab")
		)
		(fp_line
			(start -0.12065 -0.305054)
			(end -0.12065 -0.2794)
			(stroke
				(width 0.1)
				(type default)
			)
			(layer "F.Fab")
		)
		(pad "1" smd circle
			(at -0.40005 0 270)
			(size 0 0)
			(layers "F.Cu" "F.Mask" "F.Paste")
			(net "CPU0_JTAG_BUF_OE")
		)
		(pad "2" smd circle
			(at 0.40005 0 270)
			(size 0 0)
			(layers "F.Cu" "F.Mask" "F.Paste")
			(net "CPU0_JTAG_BUF_R_OE")
		)
	)
)
